# T6G (Grand Teton) — schematic netlist excerpt (pin names and nets, part order shuffled) for the footprints in the layout excerpt that follows; sources: Cadence DE-HDL packaged netlist, KiCad conversion of 04192023_DAF0TMB3IC0_F0TG_MB_C_brd_V02_OCP.brd

PC581_SOP0_1  Q_CAP  2.2UF 10V 10% X6S  pkg C0402  page 198 : A = PVDDCR_CPU0_P0_PVCC ; B = GND
C3906  Q_CAP  22UF 4V 20% X6S  pkg C0402  page 72 : A = PVDDCR_SOC_P1 ; B = GND

(kicad_pcb
	(version 20260206)
	(generator "pcbnew")
	(generator_version "10.0")
	(general
		(thickness 1.6)
		(legacy_teardrops no)
	)
	(paper "A4")
	(title_block
		(title "04192023_DAF0TMB3IC0_F0TG_MB_C_brd_V02_OCP.brd")
		(comment 1 "Grand Teton / footprints 2114-2115 of 8354")
	)
	(layers
		(0 "F.Cu" signal "TOP")
		(4 "In1.Cu" signal "GND")
		(6 "In2.Cu" signal "IN1")
		(8 "In3.Cu" signal "GND1")
		(10 "In4.Cu" signal "IN2")
		(12 "In5.Cu" signal "GND2")
		(14 "In6.Cu" signal "IN3")
		(16 "In7.Cu" signal "GND3")
		(18 "In8.Cu" signal "VCC")
		(20 "In9.Cu" signal "VCC1")
		(22 "In10.Cu" signal "GND4")
		(24 "In11.Cu" signal "IN4")
		(26 "In12.Cu" signal "GND5")
		(28 "In13.Cu" signal "IN5")
		(30 "In14.Cu" signal "GND6")
		(32 "In15.Cu" signal "IN6")
		(34 "In16.Cu" signal "GND7")
		(2 "B.Cu" signal "BOTTOM")
		(9 "F.Adhes" user "F.Adhesive")
		(11 "B.Adhes" user "B.Adhesive")
		(13 "F.Paste" user "Package Geometry/Pastemask Top")
		(15 "B.Paste" user "Package Geometry/Pastemask Bottom")
		(5 "F.SilkS" user "Ref Des/Silkscreen Top")
		(7 "B.SilkS" user "Ref Des/Silkscreen Bottom")
		(1 "F.Mask" user "Board Geometry/Soldermask Top")
		(3 "B.Mask" user "Board Geometry/Soldermask Bottom")
		(17 "Dwgs.User" user "User.Drawings")
		(19 "Cmts.User" user "User.Comments")
		(21 "Eco1.User" user "User.Eco1")
		(23 "Eco2.User" user "User.Eco2")
		(25 "Edge.Cuts" user "Board Geometry/Outline")
		(27 "Margin" user)
		(31 "F.CrtYd" user "Package Geometry/Place Bound Top")
		(29 "B.CrtYd" user "Package Geometry/Place Bound Bottom")
		(35 "F.Fab" user "Ref Des/Assembly Top")
		(33 "B.Fab" user "Ref Des/Assembly Bottom")
	)
	(footprint ""
		(layer "F.Cu")
		(at 114.325908 -256.012442 90)
		(property "Reference" "C3906"
			(at 0 0 90)
			(layer "F.SilkS")
			(hide yes)
			(effects
				(font
					(size 1.27 1.27)
				)
			)
		)
		(property "Value" ""
			(at 0 0 90)
			(layer "F.Fab")
			(effects
				(font
					(size 1.27 1.27)
				)
			)
		)
		(duplicate_pad_numbers_are_jumpers no)
		(fp_line
			(start 0.7874 -0.4064)
			(end 0.7874 0.4064)
			(stroke
				(width 0.1524)
				(type default)
			)
			(layer "F.SilkS")
		)
		(fp_line
			(start -0.7874 -0.4064)
			(end 0.7874 -0.4064)
			(stroke
				(width 0.1524)
				(type default)
			)
			(layer "F.SilkS")
		)
		(fp_line
			(start 0.7874 0.4064)
			(end -0.7874 0.4064)
			(stroke
				(width 0.1524)
				(type default)
			)
			(layer "F.SilkS")
		)
		(fp_line
			(start -0.7874 0.4064)
			(end -0.7874 -0.4064)
			(stroke
				(width 0.1524)
				(type default)
			)
			(layer "F.SilkS")
		)
		(fp_line
			(start -0.12065 -0.305054)
			(end -0.12065 -0.2794)
			(stroke
				(width 0.1)
				(type default)
			)
			(layer "F.Fab")
		)
		(fp_line
			(start -0.67945 -0.305054)
			(end -0.12065 -0.305054)
			(stroke
				(width 0.1)
				(type default)
			)
			(layer "F.Fab")
		)
		(fp_line
			(start 0.67945 -0.3048)
			(end 0.67945 0.3048)
			(stroke
				(width 0.1)
				(type default)
			)
			(layer "F.Fab")
		)
		(fp_line
			(start 0.12065 -0.3048)
			(end 0.67945 -0.3048)
			(stroke
				(width 0.1)
				(type default)
			)
			(layer "F.Fab")
		)
		(fp_line
			(start 0.12065 -0.2794)
			(end 0.12065 -0.3048)
			(stroke
				(width 0.1)
				(type default)
			)
			(layer "F.Fab")
		)
		(fp_line
			(start -0.12065 -0.2794)
			(end 0.12065 -0.2794)
			(stroke
				(width 0.1)
				(type default)
			)
			(layer "F.Fab")
		)
		(fp_line
			(start 0.120396 0.2794)
			(end -0.12065 0.2794)
			(stroke
				(width 0.1)
				(type default)
			)
			(layer "F.Fab")
		)
		(fp_line
			(start -0.12065 0.2794)
			(end -0.12065 0.3048)
			(stroke
				(width 0.1)
				(type default)
			)
			(layer "F.Fab")
		)
		(fp_line
			(start 0.67945 0.3048)
			(end 0.120396 0.3048)
			(stroke
				(width 0.1)
				(type default)
			)
			(layer "F.Fab")
		)
		(fp_line
			(start 0.120396 0.3048)
			(end 0.120396 0.2794)
			(stroke
				(width 0.1)
				(type default)
			)
			(layer "F.Fab")
		)
		(fp_line
			(start -0.12065 0.3048)
			(end -0.67945 0.3048)
			(stroke
				(width 0.1)
				(type default)
			)
			(layer "F.Fab")
		)
		(fp_line
			(start -0.67945 0.3048)
			(end -0.67945 -0.305054)
			(stroke
				(width 0.1)
				(type default)
			)
			(layer "F.Fab")
		)
		(pad "1" smd circle
			(at -0.40005 0 90)
			(size 0 0)
			(layers "F.Cu" "F.Mask" "F.Paste")
			(net "PVDDCR_SOC_P1")
		)
		(pad "2" smd circle
			(at 0.40005 0 90)
			(size 0 0)
			(layers "F.Cu" "F.Mask" "F.Paste")
			(net "GND")
		)
	)
	(footprint ""
		(layer "F.Cu")
		(at 401.507198 -177.172874 90)
		(property "Reference" "PC581_SOP0_1"
			(at 0 0 90)
			(layer "F.SilkS")
			(hide yes)
			(effects
				(font
					(size 1.27 1.27)
				)
			)
		)
		(property "Value" ""
			(at 0 0 90)
			(layer "F.Fab")
			(effects
				(font
					(size 1.27 1.27)
				)
			)
		)
		(duplicate_pad_numbers_are_jumpers no)
		(fp_line
			(start 0.7874 -0.4064)
			(end 0.7874 0.4064)
			(stroke
				(width 0.1524)
				(type default)
			)
			(layer "F.SilkS")
		)
		(fp_line
			(start -0.7874 -0.4064)
			(end 0.7874 -0.4064)
			(stroke
				(width 0.1524)
				(type default)
			)
			(layer "F.SilkS")
		)
		(fp_line
			(start 0.7874 0.4064)
			(end -0.7874 0.4064)
			(stroke
				(width 0.1524)
				(type default)
			)
			(layer "F.SilkS")
		)
		(fp_line
			(start -0.7874 0.4064)
			(end -0.7874 -0.4064)
			(stroke
				(width 0.1524)
				(type default)
			)
			(layer "F.SilkS")
		)
		(fp_line
			(start -0.12065 -0.305054)
			(end -0.12065 -0.2794)
			(stroke
				(width 0.1)
				(type default)
			)
			(layer "F.Fab")
		)
		(fp_line
			(start -0.67945 -0.305054)
			(end -0.12065 -0.305054)
			(stroke
				(width 0.1)
				(type default)
			)
			(layer "F.Fab")
		)
		(fp_line
			(start 0.67945 -0.3048)
			(end 0.67945 0.3048)
			(stroke
				(width 0.1)
				(type default)
			)
			(layer "F.Fab")
		)
		(fp_line
			(start 0.12065 -0.3048)
			(end 0.67945 -0.3048)
			(stroke
				(width 0.1)
				(type default)
			)
			(layer "F.Fab")
		)
		(fp_line
			(start 0.12065 -0.2794)
			(end 0.12065 -0.3048)
			(stroke
				(width 0.1)
				(type default)
			)
			(layer "F.Fab")
		)
		(fp_line
			(start -0.12065 -0.2794)
			(end 0.12065 -0.2794)
			(stroke
				(width 0.1)
				(type default)
			)
			(layer "F.Fab")
		)
		(fp_line
			(start 0.120396 0.2794)
			(end -0.12065 0.2794)
			(stroke
				(width 0.1)
				(type default)
			)
			(layer "F.Fab")
		)
		(fp_line
			(start -0.12065 0.2794)
			(end -0.12065 0.3048)
			(stroke
				(width 0.1)
				(type default)
			)
			(layer "F.Fab")
		)
		(fp_line
			(start 0.67945 0.3048)
			(end 0.120396 0.3048)
			(stroke
				(width 0.1)
				(type default)
			)
			(layer "F.Fab")
		)
		(fp_line
			(start 0.120396 0.3048)
			(end 0.120396 0.2794)
			(stroke
				(width 0.1)
				(type default)
			)
			(layer "F.Fab")
		)
		(fp_line
			(start -0.12065 0.3048)
			(end -0.67945 0.3048)
			(stroke
				(width 0.1)
				(type default)
			)
			(layer "F.Fab")
		)
		(fp_line
			(start -0.67945 0.3048)
			(end -0.67945 -0.305054)
			(stroke
				(width 0.1)
				(type default)
			)
			(layer "F.Fab")
		)
		(pad "1" smd circle
			(at -0.40005 0 90)
			(size 0 0)
			(layers "F.Cu" "F.Mask" "F.Paste")
			(net "PVDDCR_CPU0_P0_PVCC")
		)
		(pad "2" smd circle
			(at 0.40005 0 90)
			(size 0 0)
			(layers "F.Cu" "F.Mask" "F.Paste")
			(net "GND")
		)
	)
)
